# BASEBOARD_FAB2 (Tioga Pass) — schematic netlist excerpt (pin names and nets, part order shuffled) for the footprints in the layout excerpt that follows; sources: Cadence DE-HDL packaged netlist, KiCad conversion of Wiwynn_Tioga_Pass_MB.brd

R6W46  RES  4.75K 1% CHIP  pkg 0402  page 164 : A = PCA9554_A1 ; B = GND
R1F3  RES  0.002 1% CHIP  pkg 1206  page 197 : A = P12V_STBY ; B = P12V_NVDIMM_GHJ

(kicad_pcb
	(version 20260206)
	(generator "pcbnew")
	(generator_version "10.0")
	(general
		(thickness 1.6)
		(legacy_teardrops no)
	)
	(paper "A4")
	(title_block
		(title "Wiwynn_Tioga_Pass_MB.brd")
		(comment 1 "Tioga Pass / footprints 1774-1775 of 4770")
	)
	(layers
		(0 "F.Cu" signal "TOP")
		(4 "In1.Cu" signal "L2GND")
		(6 "In2.Cu" signal "L3")
		(8 "In3.Cu" signal "L4GND")
		(10 "In4.Cu" signal "L5")
		(12 "In5.Cu" signal "L6GND")
		(14 "In6.Cu" signal "L7VCC")
		(16 "In7.Cu" signal "L8VCC")
		(18 "In8.Cu" signal "L9GND")
		(20 "In9.Cu" signal "L10")
		(22 "In10.Cu" signal "L11GND")
		(24 "In11.Cu" signal "L12")
		(26 "In12.Cu" signal "L13GND")
		(2 "B.Cu" signal "BOTTOM")
		(9 "F.Adhes" user "F.Adhesive")
		(11 "B.Adhes" user "B.Adhesive")
		(13 "F.Paste" user "Package Geometry/Pastemask Top")
		(15 "B.Paste" user "Package Geometry/Pastemask Bottom")
		(5 "F.SilkS" user "Ref Des/Silkscreen Top")
		(7 "B.SilkS" user "Ref Des/Silkscreen Bottom")
		(1 "F.Mask" user "Board Geometry/Soldermask Top")
		(3 "B.Mask" user "Board Geometry/Soldermask Bottom")
		(17 "Dwgs.User" user "User.Drawings")
		(19 "Cmts.User" user "User.Comments")
		(21 "Eco1.User" user "User.Eco1")
		(23 "Eco2.User" user "User.Eco2")
		(25 "Edge.Cuts" user "Board Geometry/Outline")
		(27 "Margin" user)
		(31 "F.CrtYd" user "Package Geometry/Place Bound Top")
		(29 "B.CrtYd" user "Package Geometry/Place Bound Bottom")
		(35 "F.Fab" user "Ref Des/Assembly Top")
		(33 "B.Fab" user "Ref Des/Assembly Bottom")
	)
	(footprint ""
		(layer "F.Cu")
		(at 32.6263 -32.9438)
		(property "Reference" "R1F3"
			(at -0.90297 -2.159 270)
			(unlocked yes)
			(layer "F.SilkS")
			(effects
				(font
					(size 0.7874 0.5842)
					(thickness 0.1524)
				)
			)
		)
		(property "Value" ""
			(at 0 0 0)
			(layer "F.Fab")
			(effects
				(font
					(size 1.27 1.27)
				)
			)
		)
		(duplicate_pad_numbers_are_jumpers no)
		(fp_line
			(start -0.9017 1.951736)
			(end -0.9017 0.823468)
			(stroke
				(width 0.1524)
				(type default)
			)
			(layer "F.SilkS")
		)
		(fp_line
			(start 0.9017 1.952498)
			(end 0.9017 0.853948)
			(stroke
				(width 0.1524)
				(type default)
			)
			(layer "F.SilkS")
		)
		(fp_rect
			(start 0.9017 -0.3048)
			(end -0.9017 3.0988)
			(stroke
				(width 0)
				(type default)
			)
			(fill no)
			(layer "F.CrtYd")
		)
		(fp_line
			(start -0.9017 -0.3048)
			(end -0.9017 3.0988)
			(stroke
				(width 0.1)
				(type default)
			)
			(layer "F.Fab")
		)
		(fp_line
			(start -0.9017 3.0988)
			(end 0.9017 3.0988)
			(stroke
				(width 0.1)
				(type default)
			)
			(layer "F.Fab")
		)
		(fp_line
			(start 0.9017 -0.3048)
			(end -0.9017 -0.3048)
			(stroke
				(width 0.1)
				(type default)
			)
			(layer "F.Fab")
		)
		(fp_line
			(start 0.9017 3.0988)
			(end 0.9017 -0.3048)
			(stroke
				(width 0.1)
				(type default)
			)
			(layer "F.Fab")
		)
		(pad "1" smd rect
			(at 0 0)
			(size 1.524 1.016)
			(layers "F.Cu" "F.Mask" "F.Paste")
			(net "P12V_STBY")
		)
		(pad "2" smd rect
			(at 0 2.794)
			(size 1.524 1.016)
			(layers "F.Cu" "F.Mask" "F.Paste")
			(net "P12V_NVDIMM_GHJ")
		)
		(zone
			(layer "F.Cu")
			(hatch none 0.5)
			(connect_pads
				(clearance 0)
			)
			(min_thickness 0.25)
			(keepout
				(tracks allowed)
				(vias not_allowed)
				(pads allowed)
				(copperpour not_allowed)
				(footprints allowed)
			)
			(placement
				(enabled no)
				(sheetname "")
			)
			(fill
				(thermal_gap 0.5)
				(thermal_bridge_width 0.5)
				(island_removal_mode 0)
			)
			(polygon
				(pts
					(xy 33.3883 -32.4358) (xy 31.8643 -32.4358) (xy 31.8643 -30.6578) (xy 33.3883 -30.6578)
				)
			)
		)
	)
	(footprint ""
		(layer "F.Cu")
		(at 435.5338 -15.748)
		(property "Reference" "R6W46"
			(at -0.8382 -0.67818 0)
			(unlocked yes)
			(layer "F.SilkS")
			(effects
				(font
					(size 0.4064 0.254)
					(thickness 0.1524)
				)
				(justify left)
			)
		)
		(property "Value" ""
			(at 0 0 0)
			(layer "F.Fab")
			(effects
				(font
					(size 1.27 1.27)
				)
			)
		)
		(duplicate_pad_numbers_are_jumpers no)
		(fp_poly
			(pts
				(xy -0.2794 -0.1016) (xy 0.2794 -0.1016) (xy 0.2794 0.9906) (xy -0.2794 0.9906)
			)
			(stroke
				(width 0)
				(type default)
			)
			(fill no)
			(layer "F.CrtYd")
		)
		(fp_line
			(start -0.2794 -0.1016)
			(end -0.2794 0.9906)
			(stroke
				(width 0.1)
				(type default)
			)
			(layer "F.Fab")
		)
		(fp_line
			(start -0.2794 0.9906)
			(end 0.2794 0.9906)
			(stroke
				(width 0.1)
				(type default)
			)
			(layer "F.Fab")
		)
		(fp_line
			(start 0.2794 -0.1016)
			(end -0.2794 -0.1016)
			(stroke
				(width 0.1)
				(type default)
			)
			(layer "F.Fab")
		)
		(fp_line
			(start 0.2794 0.9906)
			(end 0.2794 -0.1016)
			(stroke
				(width 0.1)
				(type default)
			)
			(layer "F.Fab")
		)
		(pad "1" smd rect
			(at 0 0)
			(size 0.508 0.508)
			(layers "F.Cu" "F.Mask" "F.Paste")
			(net "PCA9554_A1")
		)
		(pad "2" smd rect
			(at 0 0.889)
			(size 0.508 0.508)
			(layers "F.Cu" "F.Mask" "F.Paste")
			(net "GND")
		)
		(zone
			(layer "F.Cu")
			(hatch none 0.5)
			(connect_pads
				(clearance 0)
			)
			(min_thickness 0.25)
			(keepout
				(tracks allowed)
				(vias not_allowed)
				(pads allowed)
				(copperpour not_allowed)
				(footprints allowed)
			)
			(placement
				(enabled no)
				(sheetname "")
			)
			(fill
				(thermal_gap 0.5)
				(thermal_bridge_width 0.5)
				(island_removal_mode 0)
			)
			(polygon
				(pts
					(xy 435.2798 -15.494) (xy 435.7878 -15.494) (xy 435.7878 -15.113) (xy 435.2798 -15.113)
				)
			)
		)
		(zone
			(layer "F.Cu")
			(hatch none 0.5)
			(connect_pads
				(clearance 0)
			)
			(min_thickness 0.25)
			(keepout
				(tracks not_allowed)
				(vias allowed)
				(pads allowed)
				(copperpour not_allowed)
				(footprints allowed)
			)
			(placement
				(enabled no)
				(sheetname "")
			)
			(fill
				(thermal_gap 0.5)
				(thermal_bridge_width 0.5)
				(island_removal_mode 0)
			)
			(polygon
				(pts
					(xy 435.2798 -15.113) (xy 435.7878 -15.113) (xy 435.7878 -15.494) (xy 435.2798 -15.494)
				)
			)
		)
	)
)
